(kicad_pcb
	(version 20260206)
	(generator "pcbnew")
	(generator_version "10.0")
	(general
		(thickness 1.6)
		(legacy_teardrops no)
	)
	(paper "A4")
	(title_block
		(title "Wiwynn_Tioga_Pass_MB.brd")
		(comment 1 "Tioga Pass / footprints 3552-3557 of 4770")
	)
	(layers
		(0 "F.Cu" signal "TOP")
		(4 "In1.Cu" signal "L2GND")
		(6 "In2.Cu" signal "L3")
		(8 "In3.Cu" signal "L4GND")
		(10 "In4.Cu" signal "L5")
		(12 "In5.Cu" signal "L6GND")
		(14 "In6.Cu" signal "L7VCC")
		(16 "In7.Cu" signal "L8VCC")
		(18 "In8.Cu" signal "L9GND")
		(20 "In9.Cu" signal "L10")
		(22 "In10.Cu" signal "L11GND")
		(24 "In11.Cu" signal "L12")
		(26 "In12.Cu" signal "L13GND")
		(2 "B.Cu" signal "BOTTOM")
		(9 "F.Adhes" user "F.Adhesive")
		(11 "B.Adhes" user "B.Adhesive")
		(13 "F.Paste" user "Package Geometry/Pastemask Top")
		(15 "B.Paste" user "Package Geometry/Pastemask Bottom")
		(5 "F.SilkS" user "Ref Des/Silkscreen Top")
		(7 "B.SilkS" user "Ref Des/Silkscreen Bottom")
		(1 "F.Mask" user "Board Geometry/Soldermask Top")
		(3 "B.Mask" user "Board Geometry/Soldermask Bottom")
		(17 "Dwgs.User" user "User.Drawings")
		(19 "Cmts.User" user "User.Comments")
		(21 "Eco1.User" user "User.Eco1")
		(23 "Eco2.User" user "User.Eco2")
		(25 "Edge.Cuts" user "Board Geometry/Outline")
		(27 "Margin" user)
		(31 "F.CrtYd" user "Package Geometry/Place Bound Top")
		(29 "B.CrtYd" user "Package Geometry/Place Bound Bottom")
		(35 "F.Fab" user "Ref Des/Assembly Top")
		(33 "B.Fab" user "Ref Des/Assembly Bottom")
	)
	(footprint ""
		(layer "B.Cu")
		(at 342.8238 -46.6598 90)
		(property "Reference" "C4R1"
			(at 3.07467 3.429 180)
			(unlocked yes)
			(layer "B.SilkS")
			(effects
				(font
					(size 0.7874 0.5842)
					(thickness 0.1524)
				)
				(justify mirror)
			)
		)
		(property "Value" ""
			(at 0 0 90)
			(layer "B.Fab")
			(effects
				(font
					(size 1.27 1.27)
				)
				(justify mirror)
			)
		)
		(duplicate_pad_numbers_are_jumpers no)
		(fp_line
			(start 2.563114 -1.616456)
			(end 2.563114 1.633728)
			(stroke
				(width 0.1524)
				(type default)
			)
			(layer "B.SilkS")
		)
		(fp_line
			(start 1.6002 -1.616456)
			(end 2.563114 -1.616456)
			(stroke
				(width 0.1524)
				(type default)
			)
			(layer "B.SilkS")
		)
		(fp_line
			(start -1.6002 -1.616456)
			(end -2.504948 -1.616456)
			(stroke
				(width 0.1524)
				(type default)
			)
			(layer "B.SilkS")
		)
		(fp_line
			(start -2.504948 -1.616456)
			(end -2.504948 1.633728)
			(stroke
				(width 0.1524)
				(type default)
			)
			(layer "B.SilkS")
		)
		(fp_line
			(start 2.563114 1.633728)
			(end 1.6002 1.633728)
			(stroke
				(width 0.1524)
				(type default)
			)
			(layer "B.SilkS")
		)
		(fp_line
			(start -2.504948 1.633728)
			(end -1.6002 1.633728)
			(stroke
				(width 0.1524)
				(type default)
			)
			(layer "B.SilkS")
		)
		(fp_line
			(start 2.286 7.366)
			(end 2.286 1.632712)
			(stroke
				(width 0.1524)
				(type default)
			)
			(layer "B.SilkS")
		)
		(fp_line
			(start 2.286 7.366)
			(end 1.60147 7.366)
			(stroke
				(width 0.1524)
				(type default)
			)
			(layer "B.SilkS")
		)
		(fp_line
			(start -2.286 7.366)
			(end -2.286 1.63195)
			(stroke
				(width 0.1524)
				(type default)
			)
			(layer "B.SilkS")
		)
		(fp_line
			(start -2.286 7.366)
			(end -1.600708 7.366)
			(stroke
				(width 0.1524)
				(type default)
			)
			(layer "B.SilkS")
		)
		(fp_rect
			(start 2.286 7.366)
			(end -2.286 -0.254)
			(stroke
				(width 0)
				(type default)
			)
			(fill no)
			(layer "B.CrtYd")
		)
		(fp_line
			(start 2.286 -0.254)
			(end -2.286 -0.254)
			(stroke
				(width 0.1)
				(type default)
			)
			(layer "B.Fab")
		)
		(fp_line
			(start -2.286 -0.254)
			(end -2.286 7.366)
			(stroke
				(width 0.1)
				(type default)
			)
			(layer "B.Fab")
		)
		(fp_line
			(start 2.286 7.366)
			(end 2.286 -0.254)
			(stroke
				(width 0.1)
				(type default)
			)
			(layer "B.Fab")
		)
		(fp_line
			(start -2.286 7.366)
			(end 2.286 7.366)
			(stroke
				(width 0.1)
				(type default)
			)
			(layer "B.Fab")
		)
		(pad "1" smd rect
			(at 0 0 270)
			(size 2.54 3.048)
			(layers "B.Cu" "B.Mask" "B.Paste")
			(net "PVCCMCP_CPU0")
		)
		(pad "2" smd rect
			(at 0 7.112 270)
			(size 2.54 3.048)
			(layers "B.Cu" "B.Mask" "B.Paste")
			(net "GND")
		)
	)
	(footprint ""
		(layer "B.Cu")
		(at 267.692886 -73.51014)
		(property "Reference" "C5P32"
			(at 0 0 0)
			(layer "B.SilkS")
			(hide yes)
			(effects
				(font
					(size 1.27 1.27)
				)
				(justify mirror)
			)
		)
		(property "Value" ""
			(at 0 0 0)
			(layer "B.Fab")
			(effects
				(font
					(size 1.27 1.27)
				)
				(justify mirror)
			)
		)
		(duplicate_pad_numbers_are_jumpers no)
		(fp_poly
			(pts
				(xy 0.7239 -0.2159) (xy -0.7239 -0.2159) (xy -0.7239 1.9939) (xy 0.7239 1.9939)
			)
			(stroke
				(width 0)
				(type default)
			)
			(fill no)
			(layer "B.CrtYd")
		)
		(fp_line
			(start -0.7239 -0.2159)
			(end 0.7239 -0.2159)
			(stroke
				(width 0.1)
				(type default)
			)
			(layer "B.Fab")
		)
		(fp_line
			(start -0.7239 1.9939)
			(end -0.7239 -0.2159)
			(stroke
				(width 0.1)
				(type default)
			)
			(layer "B.Fab")
		)
		(fp_line
			(start 0.7239 -0.2159)
			(end 0.7239 1.9939)
			(stroke
				(width 0.1)
				(type default)
			)
			(layer "B.Fab")
		)
		(fp_line
			(start 0.7239 1.9939)
			(end -0.7239 1.9939)
			(stroke
				(width 0.1)
				(type default)
			)
			(layer "B.Fab")
		)
		(pad "1" smd rect
			(at 0 0 180)
			(size 1.27 1.016)
			(layers "B.Cu" "B.Mask" "B.Paste")
			(net "PVCCIN_CPU0")
		)
		(pad "2" smd rect
			(at 0 1.778 180)
			(size 1.27 1.016)
			(layers "B.Cu" "B.Mask" "B.Paste")
			(net "GND")
		)
		(zone
			(layer "B.Cu")
			(hatch none 0.5)
			(connect_pads
				(clearance 0)
			)
			(min_thickness 0.25)
			(keepout
				(tracks not_allowed)
				(vias allowed)
				(pads allowed)
				(copperpour not_allowed)
				(footprints allowed)
			)
			(placement
				(enabled no)
				(sheetname "")
			)
			(fill
				(thermal_gap 0.5)
				(thermal_bridge_width 0.5)
				(island_removal_mode 0)
			)
			(polygon
				(pts
					(xy 268.327886 -73.00214) (xy 267.057886 -73.00214) (xy 267.057886 -72.24014) (xy 268.327886 -72.24014)
				)
			)
		)
	)
	(footprint ""
		(layer "B.Cu")
		(at 30.988 -64.262 180)
		(property "Reference" "CT26"
			(at 0.8382 -0.84963 180)
			(unlocked yes)
			(layer "B.SilkS")
			(effects
				(font
					(size 0.7874 0.5842)
					(thickness 0.1524)
				)
				(justify left mirror)
			)
		)
		(property "Value" ""
			(at 0 0 0)
			(layer "B.Fab")
			(effects
				(font
					(size 1.27 1.27)
				)
				(justify mirror)
			)
		)
		(duplicate_pad_numbers_are_jumpers no)
		(fp_poly
			(pts
				(xy -0.3048 -0.1016) (xy -0.3048 0.9906) (xy 0.3048 0.9906) (xy 0.3048 -0.1016)
			)
			(stroke
				(width 0)
				(type default)
			)
			(fill no)
			(layer "B.CrtYd")
		)
		(fp_line
			(start 0.3048 0.9906)
			(end -0.3048 0.9906)
			(stroke
				(width 0.1)
				(type default)
			)
			(layer "B.Fab")
		)
		(fp_line
			(start 0.3048 -0.1016)
			(end 0.3048 0.9906)
			(stroke
				(width 0.1)
				(type default)
			)
			(layer "B.Fab")
		)
		(fp_line
			(start -0.3048 0.9906)
			(end -0.3048 -0.1016)
			(stroke
				(width 0.1)
				(type default)
			)
			(layer "B.Fab")
		)
		(fp_line
			(start -0.3048 -0.1016)
			(end 0.3048 -0.1016)
			(stroke
				(width 0.1)
				(type default)
			)
			(layer "B.Fab")
		)
		(pad "1" smd rect
			(at 0 0)
			(size 0.508 0.508)
			(layers "B.Cu" "B.Mask" "B.Paste")
			(net "A_TSENSE_PVCCIN_CPU1")
		)
		(pad "2" smd rect
			(at 0 0.889)
			(size 0.508 0.508)
			(layers "B.Cu" "B.Mask" "B.Paste")
			(net "GND")
		)
		(zone
			(layer "B.Cu")
			(hatch none 0.5)
			(connect_pads
				(clearance 0)
			)
			(min_thickness 0.25)
			(keepout
				(tracks not_allowed)
				(vias allowed)
				(pads allowed)
				(copperpour not_allowed)
				(footprints allowed)
			)
			(placement
				(enabled no)
				(sheetname "")
			)
			(fill
				(thermal_gap 0.5)
				(thermal_bridge_width 0.5)
				(island_removal_mode 0)
			)
			(polygon
				(pts
					(xy 30.734 -64.897) (xy 31.242 -64.897) (xy 31.242 -64.516) (xy 30.734 -64.516)
				)
			)
		)
		(zone
			(layer "B.Cu")
			(hatch none 0.5)
			(connect_pads
				(clearance 0)
			)
			(min_thickness 0.25)
			(keepout
				(tracks allowed)
				(vias not_allowed)
				(pads allowed)
				(copperpour not_allowed)
				(footprints allowed)
			)
			(placement
				(enabled no)
				(sheetname "")
			)
			(fill
				(thermal_gap 0.5)
				(thermal_bridge_width 0.5)
				(island_removal_mode 0)
			)
			(polygon
				(pts
					(xy 30.734 -64.516) (xy 31.242 -64.516) (xy 31.242 -64.897) (xy 30.734 -64.897)
				)
			)
		)
	)
	(footprint ""
		(layer "B.Cu")
		(at 339.979 -27.178)
		(property "Reference" "C3T11"
			(at 0 0 0)
			(layer "B.SilkS")
			(hide yes)
			(effects
				(font
					(size 1.27 1.27)
				)
				(justify mirror)
			)
		)
		(property "Value" ""
			(at 0 0 0)
			(layer "B.Fab")
			(effects
				(font
					(size 1.27 1.27)
				)
				(justify mirror)
			)
		)
		(duplicate_pad_numbers_are_jumpers no)
		(fp_rect
			(start 0.4953 1.6002)
			(end -0.4953 -0.2032)
			(stroke
				(width 0)
				(type default)
			)
			(fill no)
			(layer "B.CrtYd")
		)
		(fp_line
			(start -0.4953 -0.2032)
			(end -0.4953 1.6002)
			(stroke
				(width 0.1)
				(type default)
			)
			(layer "B.Fab")
		)
		(fp_line
			(start -0.4953 1.6002)
			(end 0.4953 1.6002)
			(stroke
				(width 0.1)
				(type default)
			)
			(layer "B.Fab")
		)
		(fp_line
			(start 0.4953 -0.2032)
			(end -0.4953 -0.2032)
			(stroke
				(width 0.1)
				(type default)
			)
			(layer "B.Fab")
		)
		(fp_line
			(start 0.4953 1.6002)
			(end 0.4953 -0.2032)
			(stroke
				(width 0.1)
				(type default)
			)
			(layer "B.Fab")
		)
		(pad "1" smd rect
			(at 0 0 180)
			(size 0.762 0.889)
			(layers "B.Cu" "B.Mask" "B.Paste")
			(net "VR_VB_PVPP_ABC")
		)
		(pad "2" smd rect
			(at 0 1.397 180)
			(size 0.762 0.889)
			(layers "B.Cu" "B.Mask" "B.Paste")
			(net "AGND_PVPP_ABC")
		)
		(zone
			(layer "B.Cu")
			(hatch none 0.5)
			(connect_pads
				(clearance 0)
			)
			(min_thickness 0.25)
			(keepout
				(tracks not_allowed)
				(vias allowed)
				(pads allowed)
				(copperpour not_allowed)
				(footprints allowed)
			)
			(placement
				(enabled no)
				(sheetname "")
			)
			(fill
				(thermal_gap 0.5)
				(thermal_bridge_width 0.5)
				(island_removal_mode 0)
			)
			(polygon
				(pts
					(xy 340.36 -26.2255) (xy 340.36 -26.7335) (xy 339.598 -26.7335) (xy 339.598 -26.2255)
				)
			)
		)
	)
	(footprint ""
		(layer "B.Cu")
		(at 438.703974 -22.6314 -90)
		(property "Reference" "R3W6"
			(at 0.8382 -0.67818 270)
			(unlocked yes)
			(layer "B.SilkS")
			(effects
				(font
					(size 0.4064 0.254)
					(thickness 0.1524)
				)
				(justify left mirror)
			)
		)
		(property "Value" ""
			(at 0 0 90)
			(layer "B.Fab")
			(effects
				(font
					(size 1.27 1.27)
				)
				(justify mirror)
			)
		)
		(duplicate_pad_numbers_are_jumpers no)
		(fp_poly
			(pts
				(xy 0.2794 -0.1016) (xy -0.2794 -0.1016) (xy -0.2794 0.9906) (xy 0.2794 0.9906)
			)
			(stroke
				(width 0)
				(type default)
			)
			(fill no)
			(layer "B.CrtYd")
		)
		(fp_line
			(start -0.2794 0.9906)
			(end -0.2794 -0.1016)
			(stroke
				(width 0.1)
				(type default)
			)
			(layer "B.Fab")
		)
		(fp_line
			(start 0.2794 0.9906)
			(end -0.2794 0.9906)
			(stroke
				(width 0.1)
				(type default)
			)
			(layer "B.Fab")
		)
		(fp_line
			(start -0.2794 -0.1016)
			(end 0.2794 -0.1016)
			(stroke
				(width 0.1)
				(type default)
			)
			(layer "B.Fab")
		)
		(fp_line
			(start 0.2794 -0.1016)
			(end 0.2794 0.9906)
			(stroke
				(width 0.1)
				(type default)
			)
			(layer "B.Fab")
		)
		(pad "1" smd rect
			(at 0 0 90)
			(size 0.508 0.508)
			(layers "B.Cu" "B.Mask" "B.Paste")
			(net "P3V3_STBY")
		)
		(pad "2" smd rect
			(at 0 0.889 90)
			(size 0.508 0.508)
			(layers "B.Cu" "B.Mask" "B.Paste")
			(net "RST_BMC_EXTRST_N")
		)
		(zone
			(layer "B.Cu")
			(hatch none 0.5)
			(connect_pads
				(clearance 0)
			)
			(min_thickness 0.25)
			(keepout
				(tracks not_allowed)
				(vias allowed)
				(pads allowed)
				(copperpour not_allowed)
				(footprints allowed)
			)
			(placement
				(enabled no)
				(sheetname "")
			)
			(fill
				(thermal_gap 0.5)
				(thermal_bridge_width 0.5)
				(island_removal_mode 0)
			)
			(polygon
				(pts
					(xy 438.068974 -22.3774) (xy 438.068974 -22.8854) (xy 438.449974 -22.8854) (xy 438.449974 -22.3774)
				)
			)
		)
		(zone
			(layer "B.Cu")
			(hatch none 0.5)
			(connect_pads
				(clearance 0)
			)
			(min_thickness 0.25)
			(keepout
				(tracks allowed)
				(vias not_allowed)
				(pads allowed)
				(copperpour not_allowed)
				(footprints allowed)
			)
			(placement
				(enabled no)
				(sheetname "")
			)
			(fill
				(thermal_gap 0.5)
				(thermal_bridge_width 0.5)
				(island_removal_mode 0)
			)
			(polygon
				(pts
					(xy 438.449974 -22.3774) (xy 438.449974 -22.8854) (xy 438.068974 -22.8854) (xy 438.068974 -22.3774)
				)
			)
		)
	)
	(footprint ""
		(layer "B.Cu")
		(at 370.3955 -60.87872)
		(property "Reference" "U3P2"
			(at -4.435856 5.186172 180)
			(unlocked yes)
			(layer "B.SilkS")
			(effects
				(font
					(size 0.7874 0.5842)
					(thickness 0.1524)
				)
				(justify left mirror)
			)
		)
		(property "Value" ""
			(at 0 0 0)
			(layer "B.Fab")
			(effects
				(font
					(size 1.27 1.27)
				)
				(justify mirror)
			)
		)
		(duplicate_pad_numbers_are_jumpers no)
		(fp_line
			(start -4.4323 -0.64008)
			(end -4.4323 4.52628)
			(stroke
				(width 0.1524)
				(type default)
			)
			(layer "B.SilkS")
		)
		(fp_line
			(start -4.4323 4.52628)
			(end -1.5367 4.52628)
			(stroke
				(width 0.1524)
				(type default)
			)
			(layer "B.SilkS")
		)
		(fp_line
			(start -3.302 0.49022)
			(end -3.302 -0.64008)
			(stroke
				(width 0.1524)
				(type default)
			)
			(layer "B.SilkS")
		)
		(fp_line
			(start -2.667 -0.64008)
			(end -2.667 0.49022)
			(stroke
				(width 0.1524)
				(type default)
			)
			(layer "B.SilkS")
		)
		(fp_line
			(start -2.667 0.49022)
			(end -3.302 0.49022)
			(stroke
				(width 0.1524)
				(type default)
			)
			(layer "B.SilkS")
		)
		(fp_line
			(start -1.5367 -0.64008)
			(end -4.4323 -0.64008)
			(stroke
				(width 0.1524)
				(type default)
			)
			(layer "B.SilkS")
		)
		(fp_line
			(start -1.5367 4.52628)
			(end -1.5367 -0.64008)
			(stroke
				(width 0.1524)
				(type default)
			)
			(layer "B.SilkS")
		)
		(fp_circle
			(center 1.612138 -0.684784)
			(end 1.739138 -0.684784)
			(stroke
				(width 0.254)
				(type default)
			)
			(fill no)
			(layer "B.SilkS")
		)
		(fp_poly
			(pts
				(xy -0.7366 4.54152) (xy -0.7366 -0.64008) (xy -4.7244 -0.64008) (xy -5.2324 -0.64008) (xy -5.2324 4.54152)
				(xy -4.7244 4.54152)
			)
			(stroke
				(width 0)
				(type default)
			)
			(fill no)
			(layer "B.CrtYd")
		)
		(fp_line
			(start -5.2324 -0.64008)
			(end -5.2324 4.54152)
			(stroke
				(width 0.1)
				(type default)
			)
			(layer "B.Fab")
		)
		(fp_line
			(start -5.2324 4.54152)
			(end -0.7366 4.54152)
			(stroke
				(width 0.1)
				(type default)
			)
			(layer "B.Fab")
		)
		(fp_line
			(start -3.302 0.49022)
			(end -3.302 -0.64008)
			(stroke
				(width 0.1)
				(type default)
			)
			(layer "B.Fab")
		)
		(fp_line
			(start -2.667 -0.64008)
			(end -2.667 0.49022)
			(stroke
				(width 0.1)
				(type default)
			)
			(layer "B.Fab")
		)
		(fp_line
			(start -2.667 0.49022)
			(end -3.302 0.49022)
			(stroke
				(width 0.1)
				(type default)
			)
			(layer "B.Fab")
		)
		(fp_line
			(start -0.7366 -0.64008)
			(end -5.2324 -0.64008)
			(stroke
				(width 0.1)
				(type default)
			)
			(layer "B.Fab")
		)
		(fp_line
			(start -0.7366 4.54152)
			(end -0.7366 -0.64008)
			(stroke
				(width 0.1)
				(type default)
			)
			(layer "B.Fab")
		)
		(fp_circle
			(center 1.612138 -0.684784)
			(end 1.739138 -0.684784)
			(stroke
				(width 0.254)
				(type default)
			)
			(fill no)
			(layer "B.Fab")
		)
		(pad "1" smd rect
			(at 0 0 180)
			(size 2.159 0.381)
			(layers "B.Cu" "B.Mask" "B.Paste")
			(net "PD_GTL2104_DIR_1")
		)
		(pad "2" smd rect
			(at 0 0.65024 180)
			(size 2.159 0.381)
			(layers "B.Cu" "B.Mask" "B.Paste")
			(net "PWRGD_CPUPWRGD_GTL")
		)
		(pad "3" smd rect
			(at 0 1.30048 180)
			(size 2.159 0.381)
			(layers "B.Cu" "B.Mask" "B.Paste")
			(net "H_CPU1_FIVR_FAULT_G")
		)
		(pad "4" smd rect
			(at 0 1.95072 180)
			(size 2.159 0.381)
			(layers "B.Cu" "B.Mask" "B.Paste")
			(net "P0V7_GTL2104_VREF_1")
		)
		(pad "5" smd rect
			(at 0 2.60096 180)
			(size 2.159 0.381)
			(layers "B.Cu" "B.Mask" "B.Paste")
			(net "H_CPU_CATERR_G_N")
		)
		(pad "6" smd rect
			(at 0 3.2512 180)
			(size 2.159 0.381)
			(layers "B.Cu" "B.Mask" "B.Paste")
			(net "H_CPU1_THERMTRIP_G_N")
		)
		(pad "7" smd rect
			(at 0 3.90144 180)
			(size 2.159 0.381)
			(layers "B.Cu" "B.Mask" "B.Paste")
			(net "GND")
		)
		(pad "8" smd rect
			(at -5.969 3.90144 180)
			(size 2.159 0.381)
			(layers "B.Cu" "B.Mask" "B.Paste")
			(net "GND")
		)
		(pad "9" smd rect
			(at -5.969 3.2512 180)
			(size 2.159 0.381)
			(layers "B.Cu" "B.Mask" "B.Paste")
			(net "FM_CPU1_THERMTRIP_LVT3_R_N")
		)
		(pad "10" smd rect
			(at -5.969 2.60096 180)
			(size 2.159 0.381)
			(layers "B.Cu" "B.Mask" "B.Paste")
			(net "FM_CPU_CATERR_LVT3_R2_N")
		)
		(pad "11" smd rect
			(at -5.969 1.95072 180)
			(size 2.159 0.381)
			(layers "B.Cu" "B.Mask" "B.Paste")
			(net "GND")
		)
		(pad "12" smd rect
			(at -5.969 1.30048 180)
			(size 2.159 0.381)
			(layers "B.Cu" "B.Mask" "B.Paste")
			(net "FM_CPU1_FIVR_FAULT_R_LVT3")
		)
		(pad "13" smd rect
			(at -5.969 0.65024 180)
			(size 2.159 0.381)
			(layers "B.Cu" "B.Mask" "B.Paste")
			(net "PWRGD_CPUPWRGD_R1")
		)
		(pad "14" smd rect
			(at -5.969 0 180)
			(size 2.159 0.381)
			(layers "B.Cu" "B.Mask" "B.Paste")
			(net "P3V3")
		)
	)
)
